(kicad_pcb
	(version 20260206)
	(generator "pcbnew")
	(generator_version "10.0")
	(general
		(thickness 1.6)
		(legacy_teardrops no)
	)
	(paper "A4")
	(title_block
		(title "Wiwynn_Tioga_Pass_MB.brd")
		(comment 1 "Tioga Pass / footprints 815-821 of 4770")
	)
	(layers
		(0 "F.Cu" signal "TOP")
		(4 "In1.Cu" signal "L2GND")
		(6 "In2.Cu" signal "L3")
		(8 "In3.Cu" signal "L4GND")
		(10 "In4.Cu" signal "L5")
		(12 "In5.Cu" signal "L6GND")
		(14 "In6.Cu" signal "L7VCC")
		(16 "In7.Cu" signal "L8VCC")
		(18 "In8.Cu" signal "L9GND")
		(20 "In9.Cu" signal "L10")
		(22 "In10.Cu" signal "L11GND")
		(24 "In11.Cu" signal "L12")
		(26 "In12.Cu" signal "L13GND")
		(2 "B.Cu" signal "BOTTOM")
		(9 "F.Adhes" user "F.Adhesive")
		(11 "B.Adhes" user "B.Adhesive")
		(13 "F.Paste" user "Package Geometry/Pastemask Top")
		(15 "B.Paste" user "Package Geometry/Pastemask Bottom")
		(5 "F.SilkS" user "Ref Des/Silkscreen Top")
		(7 "B.SilkS" user "Ref Des/Silkscreen Bottom")
		(1 "F.Mask" user "Board Geometry/Soldermask Top")
		(3 "B.Mask" user "Board Geometry/Soldermask Bottom")
		(17 "Dwgs.User" user "User.Drawings")
		(19 "Cmts.User" user "User.Comments")
		(21 "Eco1.User" user "User.Eco1")
		(23 "Eco2.User" user "User.Eco2")
		(25 "Edge.Cuts" user "Board Geometry/Outline")
		(27 "Margin" user)
		(31 "F.CrtYd" user "Package Geometry/Place Bound Top")
		(29 "B.CrtYd" user "Package Geometry/Place Bound Bottom")
		(35 "F.Fab" user "Ref Des/Assembly Top")
		(33 "B.Fab" user "Ref Des/Assembly Bottom")
	)
	(footprint ""
		(layer "F.Cu")
		(at 452.12 -153.543 -90)
		(property "Reference" "R9A1"
			(at 0 0 270)
			(layer "F.SilkS")
			(hide yes)
			(effects
				(font
					(size 1.27 1.27)
				)
			)
		)
		(property "Value" ""
			(at 0 0 270)
			(layer "F.Fab")
			(effects
				(font
					(size 1.27 1.27)
				)
			)
		)
		(duplicate_pad_numbers_are_jumpers no)
		(fp_poly
			(pts
				(xy -0.2794 -0.1016) (xy 0.2794 -0.1016) (xy 0.2794 0.9906) (xy -0.2794 0.9906)
			)
			(stroke
				(width 0)
				(type default)
			)
			(fill no)
			(layer "F.CrtYd")
		)
		(fp_line
			(start -0.2794 0.9906)
			(end 0.2794 0.9906)
			(stroke
				(width 0.1)
				(type default)
			)
			(layer "F.Fab")
		)
		(fp_line
			(start 0.2794 0.9906)
			(end 0.2794 -0.1016)
			(stroke
				(width 0.1)
				(type default)
			)
			(layer "F.Fab")
		)
		(fp_line
			(start -0.2794 -0.1016)
			(end -0.2794 0.9906)
			(stroke
				(width 0.1)
				(type default)
			)
			(layer "F.Fab")
		)
		(fp_line
			(start 0.2794 -0.1016)
			(end -0.2794 -0.1016)
			(stroke
				(width 0.1)
				(type default)
			)
			(layer "F.Fab")
		)
		(pad "1" smd rect
			(at 0 0 270)
			(size 0.508 0.508)
			(layers "F.Cu" "F.Mask" "F.Paste")
			(net "P3V3")
		)
		(pad "2" smd rect
			(at 0 0.889 270)
			(size 0.508 0.508)
			(layers "F.Cu" "F.Mask" "F.Paste")
			(net "XDP_CPU_TCK_BUF")
		)
		(zone
			(layer "F.Cu")
			(hatch none 0.5)
			(connect_pads
				(clearance 0)
			)
			(min_thickness 0.25)
			(keepout
				(tracks not_allowed)
				(vias allowed)
				(pads allowed)
				(copperpour not_allowed)
				(footprints allowed)
			)
			(placement
				(enabled no)
				(sheetname "")
			)
			(fill
				(thermal_gap 0.5)
				(thermal_bridge_width 0.5)
				(island_removal_mode 0)
			)
			(polygon
				(pts
					(xy 451.485 -153.797) (xy 451.485 -153.289) (xy 451.866 -153.289) (xy 451.866 -153.797)
				)
			)
		)
		(zone
			(layer "F.Cu")
			(hatch none 0.5)
			(connect_pads
				(clearance 0)
			)
			(min_thickness 0.25)
			(keepout
				(tracks allowed)
				(vias not_allowed)
				(pads allowed)
				(copperpour not_allowed)
				(footprints allowed)
			)
			(placement
				(enabled no)
				(sheetname "")
			)
			(fill
				(thermal_gap 0.5)
				(thermal_bridge_width 0.5)
				(island_removal_mode 0)
			)
			(polygon
				(pts
					(xy 451.866 -153.797) (xy 451.866 -153.289) (xy 451.485 -153.289) (xy 451.485 -153.797)
				)
			)
		)
	)
	(footprint ""
		(layer "F.Cu")
		(at 257.8608 -149.733 -90)
		(property "Reference" "C5A5"
			(at 0 0 270)
			(layer "F.SilkS")
			(hide yes)
			(effects
				(font
					(size 1.27 1.27)
				)
			)
		)
		(property "Value" ""
			(at 0 0 270)
			(layer "F.Fab")
			(effects
				(font
					(size 1.27 1.27)
				)
			)
		)
		(duplicate_pad_numbers_are_jumpers no)
		(fp_rect
			(start -0.500126 1.598422)
			(end 0.500126 -0.201422)
			(stroke
				(width 0)
				(type default)
			)
			(fill no)
			(layer "F.CrtYd")
		)
		(fp_line
			(start -0.500126 1.598422)
			(end -0.500126 -0.201422)
			(stroke
				(width 0.1)
				(type default)
			)
			(layer "F.Fab")
		)
		(fp_line
			(start 0.500126 1.598422)
			(end -0.500126 1.598422)
			(stroke
				(width 0.1)
				(type default)
			)
			(layer "F.Fab")
		)
		(fp_line
			(start -0.500126 -0.201422)
			(end 0.500126 -0.201422)
			(stroke
				(width 0.1)
				(type default)
			)
			(layer "F.Fab")
		)
		(fp_line
			(start 0.500126 -0.201422)
			(end 0.500126 1.598422)
			(stroke
				(width 0.1)
				(type default)
			)
			(layer "F.Fab")
		)
		(pad "1" smd rect
			(at 0 0 180)
			(size 0.889 0.9906)
			(layers "F.Cu" "F.Mask" "F.Paste")
			(net "PVDDQ_DEF")
		)
		(pad "2" smd rect
			(at 0 1.397 180)
			(size 0.889 0.9906)
			(layers "F.Cu" "F.Mask" "F.Paste")
			(net "GND")
		)
		(zone
			(layer "F.Cu")
			(hatch none 0.5)
			(connect_pads
				(clearance 0)
			)
			(min_thickness 0.25)
			(keepout
				(tracks allowed)
				(vias not_allowed)
				(pads allowed)
				(copperpour not_allowed)
				(footprints allowed)
			)
			(placement
				(enabled no)
				(sheetname "")
			)
			(fill
				(thermal_gap 0.5)
				(thermal_bridge_width 0.5)
				(island_removal_mode 0)
			)
			(polygon
				(pts
					(xy 256.9083 -150.2283) (xy 256.9083 -149.2377) (xy 257.4163 -149.2377) (xy 257.4163 -150.2283)
				)
			)
		)
		(zone
			(layer "F.Cu")
			(hatch none 0.5)
			(connect_pads
				(clearance 0)
			)
			(min_thickness 0.25)
			(keepout
				(tracks not_allowed)
				(vias allowed)
				(pads allowed)
				(copperpour not_allowed)
				(footprints allowed)
			)
			(placement
				(enabled no)
				(sheetname "")
			)
			(fill
				(thermal_gap 0.5)
				(thermal_bridge_width 0.5)
				(island_removal_mode 0)
			)
			(polygon
				(pts
					(xy 256.9083 -150.2283) (xy 256.9083 -149.2377) (xy 257.4163 -149.2377) (xy 257.4163 -150.2283)
				)
			)
		)
	)
	(footprint ""
		(layer "F.Cu")
		(at 400.685 -84.0105 180)
		(property "Reference" "R2P14"
			(at 0 0 180)
			(layer "F.SilkS")
			(hide yes)
			(effects
				(font
					(size 1.27 1.27)
				)
			)
		)
		(property "Value" ""
			(at 0 0 180)
			(layer "F.Fab")
			(effects
				(font
					(size 1.27 1.27)
				)
			)
		)
		(duplicate_pad_numbers_are_jumpers no)
		(fp_poly
			(pts
				(xy -0.2794 -0.1016) (xy 0.2794 -0.1016) (xy 0.2794 0.9906) (xy -0.2794 0.9906)
			)
			(stroke
				(width 0)
				(type default)
			)
			(fill no)
			(layer "F.CrtYd")
		)
		(fp_line
			(start 0.2794 0.9906)
			(end 0.2794 -0.1016)
			(stroke
				(width 0.1)
				(type default)
			)
			(layer "F.Fab")
		)
		(fp_line
			(start 0.2794 -0.1016)
			(end -0.2794 -0.1016)
			(stroke
				(width 0.1)
				(type default)
			)
			(layer "F.Fab")
		)
		(fp_line
			(start -0.2794 0.9906)
			(end 0.2794 0.9906)
			(stroke
				(width 0.1)
				(type default)
			)
			(layer "F.Fab")
		)
		(fp_line
			(start -0.2794 -0.1016)
			(end -0.2794 0.9906)
			(stroke
				(width 0.1)
				(type default)
			)
			(layer "F.Fab")
		)
		(pad "1" smd rect
			(at 0 0 180)
			(size 0.508 0.508)
			(layers "F.Cu" "F.Mask" "F.Paste")
			(net "FM_M2_DET_LVC3")
		)
		(pad "2" smd rect
			(at 0 0.889 180)
			(size 0.508 0.508)
			(layers "F.Cu" "F.Mask" "F.Paste")
			(net "FM_SSATA_PCIE_M2_SEL")
		)
		(zone
			(layer "F.Cu")
			(hatch none 0.5)
			(connect_pads
				(clearance 0)
			)
			(min_thickness 0.25)
			(keepout
				(tracks not_allowed)
				(vias allowed)
				(pads allowed)
				(copperpour not_allowed)
				(footprints allowed)
			)
			(placement
				(enabled no)
				(sheetname "")
			)
			(fill
				(thermal_gap 0.5)
				(thermal_bridge_width 0.5)
				(island_removal_mode 0)
			)
			(polygon
				(pts
					(xy 400.939 -84.6455) (xy 400.431 -84.6455) (xy 400.431 -84.2645) (xy 400.939 -84.2645)
				)
			)
		)
		(zone
			(layer "F.Cu")
			(hatch none 0.5)
			(connect_pads
				(clearance 0)
			)
			(min_thickness 0.25)
			(keepout
				(tracks allowed)
				(vias not_allowed)
				(pads allowed)
				(copperpour not_allowed)
				(footprints allowed)
			)
			(placement
				(enabled no)
				(sheetname "")
			)
			(fill
				(thermal_gap 0.5)
				(thermal_bridge_width 0.5)
				(island_removal_mode 0)
			)
			(polygon
				(pts
					(xy 400.939 -84.2645) (xy 400.431 -84.2645) (xy 400.431 -84.6455) (xy 400.939 -84.6455)
				)
			)
		)
	)
	(footprint ""
		(layer "F.Cu")
		(at 410.817822 -11.436858)
		(property "Reference" "C8G10"
			(at 0 0 0)
			(layer "F.SilkS")
			(hide yes)
			(effects
				(font
					(size 1.27 1.27)
				)
			)
		)
		(property "Value" ""
			(at 0 0 0)
			(layer "F.Fab")
			(effects
				(font
					(size 1.27 1.27)
				)
			)
		)
		(duplicate_pad_numbers_are_jumpers no)
		(fp_rect
			(start -0.3048 0.9906)
			(end 0.3048 -0.1016)
			(stroke
				(width 0)
				(type default)
			)
			(fill no)
			(layer "F.CrtYd")
		)
		(fp_line
			(start -0.3048 -0.1016)
			(end -0.3048 0.9906)
			(stroke
				(width 0.1)
				(type default)
			)
			(layer "F.Fab")
		)
		(fp_line
			(start -0.3048 0.9906)
			(end 0.3048 0.9906)
			(stroke
				(width 0.1)
				(type default)
			)
			(layer "F.Fab")
		)
		(fp_line
			(start 0.3048 -0.1016)
			(end -0.3048 -0.1016)
			(stroke
				(width 0.1)
				(type default)
			)
			(layer "F.Fab")
		)
		(fp_line
			(start 0.3048 0.9906)
			(end 0.3048 -0.1016)
			(stroke
				(width 0.1)
				(type default)
			)
			(layer "F.Fab")
		)
		(pad "1" smd rect
			(at 0 0)
			(size 0.508 0.508)
			(layers "F.Cu" "F.Mask" "F.Paste")
			(net "P3E_CPU0_PE2_SS_TXN<0>")
		)
		(pad "2" smd rect
			(at 0 0.889)
			(size 0.508 0.508)
			(layers "F.Cu" "F.Mask" "F.Paste")
			(net "P3E_CPU0_PE2_SS_C_TXN<0>")
		)
		(zone
			(layer "F.Cu")
			(hatch none 0.5)
			(connect_pads
				(clearance 0)
			)
			(min_thickness 0.25)
			(keepout
				(tracks allowed)
				(vias not_allowed)
				(pads allowed)
				(copperpour not_allowed)
				(footprints allowed)
			)
			(placement
				(enabled no)
				(sheetname "")
			)
			(fill
				(thermal_gap 0.5)
				(thermal_bridge_width 0.5)
				(island_removal_mode 0)
			)
			(polygon
				(pts
					(xy 410.563822 -10.801858) (xy 411.071822 -10.801858) (xy 411.071822 -11.182858) (xy 410.563822 -11.182858)
				)
			)
		)
		(zone
			(layer "F.Cu")
			(hatch none 0.5)
			(connect_pads
				(clearance 0)
			)
			(min_thickness 0.25)
			(keepout
				(tracks not_allowed)
				(vias allowed)
				(pads allowed)
				(copperpour not_allowed)
				(footprints allowed)
			)
			(placement
				(enabled no)
				(sheetname "")
			)
			(fill
				(thermal_gap 0.5)
				(thermal_bridge_width 0.5)
				(island_removal_mode 0)
			)
			(polygon
				(pts
					(xy 410.563822 -10.801858) (xy 411.071822 -10.801858) (xy 411.071822 -11.182858) (xy 410.563822 -11.182858)
				)
			)
		)
	)
	(footprint ""
		(layer "F.Cu")
		(at 491.1471 -48.2854 -90)
		(property "Reference" "R9E6"
			(at 0 0 270)
			(layer "F.SilkS")
			(hide yes)
			(effects
				(font
					(size 1.27 1.27)
				)
			)
		)
		(property "Value" ""
			(at 0 0 270)
			(layer "F.Fab")
			(effects
				(font
					(size 1.27 1.27)
				)
			)
		)
		(duplicate_pad_numbers_are_jumpers no)
		(fp_poly
			(pts
				(xy -0.2794 -0.1016) (xy 0.2794 -0.1016) (xy 0.2794 0.9906) (xy -0.2794 0.9906)
			)
			(stroke
				(width 0)
				(type default)
			)
			(fill no)
			(layer "F.CrtYd")
		)
		(fp_line
			(start -0.2794 0.9906)
			(end 0.2794 0.9906)
			(stroke
				(width 0.1)
				(type default)
			)
			(layer "F.Fab")
		)
		(fp_line
			(start 0.2794 0.9906)
			(end 0.2794 -0.1016)
			(stroke
				(width 0.1)
				(type default)
			)
			(layer "F.Fab")
		)
		(fp_line
			(start -0.2794 -0.1016)
			(end -0.2794 0.9906)
			(stroke
				(width 0.1)
				(type default)
			)
			(layer "F.Fab")
		)
		(fp_line
			(start 0.2794 -0.1016)
			(end -0.2794 -0.1016)
			(stroke
				(width 0.1)
				(type default)
			)
			(layer "F.Fab")
		)
		(pad "1" smd rect
			(at 0 0 270)
			(size 0.508 0.508)
			(layers "F.Cu" "F.Mask" "F.Paste")
			(net "SPI_NIC_MISO_R")
		)
		(pad "2" smd rect
			(at 0 0.889 270)
			(size 0.508 0.508)
			(layers "F.Cu" "F.Mask" "F.Paste")
			(net "SPI_NIC_MISO")
		)
		(zone
			(layer "F.Cu")
			(hatch none 0.5)
			(connect_pads
				(clearance 0)
			)
			(min_thickness 0.25)
			(keepout
				(tracks not_allowed)
				(vias allowed)
				(pads allowed)
				(copperpour not_allowed)
				(footprints allowed)
			)
			(placement
				(enabled no)
				(sheetname "")
			)
			(fill
				(thermal_gap 0.5)
				(thermal_bridge_width 0.5)
				(island_removal_mode 0)
			)
			(polygon
				(pts
					(xy 490.5121 -48.5394) (xy 490.5121 -48.0314) (xy 490.8931 -48.0314) (xy 490.8931 -48.5394)
				)
			)
		)
		(zone
			(layer "F.Cu")
			(hatch none 0.5)
			(connect_pads
				(clearance 0)
			)
			(min_thickness 0.25)
			(keepout
				(tracks allowed)
				(vias not_allowed)
				(pads allowed)
				(copperpour not_allowed)
				(footprints allowed)
			)
			(placement
				(enabled no)
				(sheetname "")
			)
			(fill
				(thermal_gap 0.5)
				(thermal_bridge_width 0.5)
				(island_removal_mode 0)
			)
			(polygon
				(pts
					(xy 490.8931 -48.5394) (xy 490.8931 -48.0314) (xy 490.5121 -48.0314) (xy 490.5121 -48.5394)
				)
			)
		)
	)
	(footprint ""
		(layer "F.Cu")
		(at -3.22326 -132.86486)
		(property "Reference" "R1B1"
			(at 0 0 0)
			(layer "F.SilkS")
			(hide yes)
			(effects
				(font
					(size 1.27 1.27)
				)
			)
		)
		(property "Value" ""
			(at 0 0 0)
			(layer "F.Fab")
			(effects
				(font
					(size 1.27 1.27)
				)
			)
		)
		(duplicate_pad_numbers_are_jumpers no)
		(fp_poly
			(pts
				(xy -0.2794 -0.1016) (xy 0.2794 -0.1016) (xy 0.2794 0.9906) (xy -0.2794 0.9906)
			)
			(stroke
				(width 0)
				(type default)
			)
			(fill no)
			(layer "F.CrtYd")
		)
		(fp_line
			(start -0.2794 -0.1016)
			(end -0.2794 0.9906)
			(stroke
				(width 0.1)
				(type default)
			)
			(layer "F.Fab")
		)
		(fp_line
			(start -0.2794 0.9906)
			(end 0.2794 0.9906)
			(stroke
				(width 0.1)
				(type default)
			)
			(layer "F.Fab")
		)
		(fp_line
			(start 0.2794 -0.1016)
			(end -0.2794 -0.1016)
			(stroke
				(width 0.1)
				(type default)
			)
			(layer "F.Fab")
		)
		(fp_line
			(start 0.2794 0.9906)
			(end 0.2794 -0.1016)
			(stroke
				(width 0.1)
				(type default)
			)
			(layer "F.Fab")
		)
		(pad "1" smd rect
			(at 0 0)
			(size 0.508 0.508)
			(layers "F.Cu" "F.Mask" "F.Paste")
			(net "P3V3_STBY")
		)
		(pad "2" smd rect
			(at 0 0.889)
			(size 0.508 0.508)
			(layers "F.Cu" "F.Mask" "F.Paste")
			(net "IRQ_PVDDQ_KLM_VRHOT_LVT3_R_N")
		)
		(zone
			(layer "F.Cu")
			(hatch none 0.5)
			(connect_pads
				(clearance 0)
			)
			(min_thickness 0.25)
			(keepout
				(tracks allowed)
				(vias not_allowed)
				(pads allowed)
				(copperpour not_allowed)
				(footprints allowed)
			)
			(placement
				(enabled no)
				(sheetname "")
			)
			(fill
				(thermal_gap 0.5)
				(thermal_bridge_width 0.5)
				(island_removal_mode 0)
			)
			(polygon
				(pts
					(xy -3.47726 -132.61086) (xy -2.96926 -132.61086) (xy -2.96926 -132.22986) (xy -3.47726 -132.22986)
				)
			)
		)
		(zone
			(layer "F.Cu")
			(hatch none 0.5)
			(connect_pads
				(clearance 0)
			)
			(min_thickness 0.25)
			(keepout
				(tracks not_allowed)
				(vias allowed)
				(pads allowed)
				(copperpour not_allowed)
				(footprints allowed)
			)
			(placement
				(enabled no)
				(sheetname "")
			)
			(fill
				(thermal_gap 0.5)
				(thermal_bridge_width 0.5)
				(island_removal_mode 0)
			)
			(polygon
				(pts
					(xy -3.47726 -132.22986) (xy -2.96926 -132.22986) (xy -2.96926 -132.61086) (xy -3.47726 -132.61086)
				)
			)
		)
	)
	(footprint ""
		(layer "F.Cu")
		(at 341.9348 -32.8803 90)
		(property "Reference" "C7F3"
			(at 0 0 90)
			(layer "F.SilkS")
			(hide yes)
			(effects
				(font
					(size 1.27 1.27)
				)
			)
		)
		(property "Value" ""
			(at 0 0 90)
			(layer "F.Fab")
			(effects
				(font
					(size 1.27 1.27)
				)
			)
		)
		(duplicate_pad_numbers_are_jumpers no)
		(fp_rect
			(start -0.3048 -0.1016)
			(end 0.3048 0.9906)
			(stroke
				(width 0)
				(type default)
			)
			(fill no)
			(layer "F.CrtYd")
		)
		(fp_line
			(start 0.3048 -0.1016)
			(end -0.3048 -0.1016)
			(stroke
				(width 0.1)
				(type default)
			)
			(layer "F.Fab")
		)
		(fp_line
			(start -0.3048 -0.1016)
			(end -0.3048 0.9906)
			(stroke
				(width 0.1)
				(type default)
			)
			(layer "F.Fab")
		)
		(fp_line
			(start 0.3048 0.9906)
			(end 0.3048 -0.1016)
			(stroke
				(width 0.1)
				(type default)
			)
			(layer "F.Fab")
		)
		(fp_line
			(start -0.3048 0.9906)
			(end 0.3048 0.9906)
			(stroke
				(width 0.1)
				(type default)
			)
			(layer "F.Fab")
		)
		(pad "1" smd rect
			(at 0 0 90)
			(size 0.508 0.508)
			(layers "F.Cu" "F.Mask" "F.Paste")
			(net "VR_PVPP_ABC_PHASE")
		)
		(pad "2" smd rect
			(at 0 0.889 90)
			(size 0.508 0.508)
			(layers "F.Cu" "F.Mask" "F.Paste")
			(net "VR_PVPP_ABC_SNUB")
		)
		(zone
			(layer "F.Cu")
			(hatch none 0.5)
			(connect_pads
				(clearance 0)
			)
			(min_thickness 0.25)
			(keepout
				(tracks allowed)
				(vias not_allowed)
				(pads allowed)
				(copperpour not_allowed)
				(footprints allowed)
			)
			(placement
				(enabled no)
				(sheetname "")
			)
			(fill
				(thermal_gap 0.5)
				(thermal_bridge_width 0.5)
				(island_removal_mode 0)
			)
			(polygon
				(pts
					(xy 342.1888 -32.6263) (xy 342.5698 -32.6263) (xy 342.5698 -33.1343) (xy 342.1888 -33.1343)
				)
			)
		)
		(zone
			(layer "F.Cu")
			(hatch none 0.5)
			(connect_pads
				(clearance 0)
			)
			(min_thickness 0.25)
			(keepout
				(tracks not_allowed)
				(vias allowed)
				(pads allowed)
				(copperpour not_allowed)
				(footprints allowed)
			)
			(placement
				(enabled no)
				(sheetname "")
			)
			(fill
				(thermal_gap 0.5)
				(thermal_bridge_width 0.5)
				(island_removal_mode 0)
			)
			(polygon
				(pts
					(xy 342.1888 -32.6263) (xy 342.5698 -32.6263) (xy 342.5698 -33.1343) (xy 342.1888 -33.1343)
				)
			)
		)
	)
)
